# BASEBOARD_FAB2 (Tioga Pass) — schematic netlist excerpt (pin names and nets, part order shuffled) for the footprints in the layout excerpt that follows; sources: Cadence DE-HDL packaged netlist, KiCad conversion of Wiwynn_Tioga_Pass_MB.brd

C2T33  CAP_A  1.0UF 6.3V 10% X6S  pkg 0402V  page 93 : A = P3V3 ; B = GND
C5G58  CAP_A  22.0UF 4V 20% X6S  pkg 0603V  page 242 : A = PVDDQ_ABC ; B = GND
R1M15  RES  0.0 5% CHIP  pkg 0402  page 186 : A = RMII_BMC_OCP_CRSDV ; B = RMII_BMC_OCP_CRSDV_R

(kicad_pcb
	(version 20260206)
	(generator "pcbnew")
	(generator_version "10.0")
	(general
		(thickness 1.6)
		(legacy_teardrops no)
	)
	(paper "A4")
	(title_block
		(title "Wiwynn_Tioga_Pass_MB.brd")
		(comment 1 "Tioga Pass / footprints 4727-4729 of 4770")
	)
	(layers
		(0 "F.Cu" signal "TOP")
		(4 "In1.Cu" signal "L2GND")
		(6 "In2.Cu" signal "L3")
		(8 "In3.Cu" signal "L4GND")
		(10 "In4.Cu" signal "L5")
		(12 "In5.Cu" signal "L6GND")
		(14 "In6.Cu" signal "L7VCC")
		(16 "In7.Cu" signal "L8VCC")
		(18 "In8.Cu" signal "L9GND")
		(20 "In9.Cu" signal "L10")
		(22 "In10.Cu" signal "L11GND")
		(24 "In11.Cu" signal "L12")
		(26 "In12.Cu" signal "L13GND")
		(2 "B.Cu" signal "BOTTOM")
		(9 "F.Adhes" user "F.Adhesive")
		(11 "B.Adhes" user "B.Adhesive")
		(13 "F.Paste" user "Package Geometry/Pastemask Top")
		(15 "B.Paste" user "Package Geometry/Pastemask Bottom")
		(5 "F.SilkS" user "Ref Des/Silkscreen Top")
		(7 "B.SilkS" user "Ref Des/Silkscreen Bottom")
		(1 "F.Mask" user "Board Geometry/Soldermask Top")
		(3 "B.Mask" user "Board Geometry/Soldermask Bottom")
		(17 "Dwgs.User" user "User.Drawings")
		(19 "Cmts.User" user "User.Comments")
		(21 "Eco1.User" user "User.Eco1")
		(23 "Eco2.User" user "User.Eco2")
		(25 "Edge.Cuts" user "Board Geometry/Outline")
		(27 "Margin" user)
		(31 "F.CrtYd" user "Package Geometry/Place Bound Top")
		(29 "B.CrtYd" user "Package Geometry/Place Bound Bottom")
		(35 "F.Fab" user "Ref Des/Assembly Top")
		(33 "B.Fab" user "Ref Des/Assembly Bottom")
	)
	(footprint ""
		(layer "B.Cu")
		(at 272.861532 -3.3528 90)
		(property "Reference" "C5G58"
			(at -1.14681 0.76708 180)
			(unlocked yes)
			(layer "B.SilkS")
			(effects
				(font
					(size 0.7874 0.5842)
					(thickness 0.1524)
				)
				(justify mirror)
			)
		)
		(property "Value" ""
			(at 0 0 90)
			(layer "B.Fab")
			(effects
				(font
					(size 1.27 1.27)
				)
				(justify mirror)
			)
		)
		(duplicate_pad_numbers_are_jumpers no)
		(fp_rect
			(start -0.4953 -0.2032)
			(end 0.4953 1.6002)
			(stroke
				(width 0)
				(type default)
			)
			(fill no)
			(layer "B.CrtYd")
		)
		(fp_line
			(start 0.4953 -0.2032)
			(end -0.4953 -0.2032)
			(stroke
				(width 0.1)
				(type default)
			)
			(layer "B.Fab")
		)
		(fp_line
			(start -0.4953 -0.2032)
			(end -0.4953 1.6002)
			(stroke
				(width 0.1)
				(type default)
			)
			(layer "B.Fab")
		)
		(fp_line
			(start 0.4953 1.6002)
			(end 0.4953 -0.2032)
			(stroke
				(width 0.1)
				(type default)
			)
			(layer "B.Fab")
		)
		(fp_line
			(start -0.4953 1.6002)
			(end 0.4953 1.6002)
			(stroke
				(width 0.1)
				(type default)
			)
			(layer "B.Fab")
		)
		(pad "1" smd rect
			(at 0 0 270)
			(size 0.762 0.889)
			(layers "B.Cu" "B.Mask" "B.Paste")
			(net "PVDDQ_ABC")
		)
		(pad "2" smd rect
			(at 0 1.397 270)
			(size 0.762 0.889)
			(layers "B.Cu" "B.Mask" "B.Paste")
			(net "GND")
		)
		(zone
			(layer "B.Cu")
			(hatch none 0.5)
			(connect_pads
				(clearance 0)
			)
			(min_thickness 0.25)
			(keepout
				(tracks not_allowed)
				(vias allowed)
				(pads allowed)
				(copperpour not_allowed)
				(footprints allowed)
			)
			(placement
				(enabled no)
				(sheetname "")
			)
			(fill
				(thermal_gap 0.5)
				(thermal_bridge_width 0.5)
				(island_removal_mode 0)
			)
			(polygon
				(pts
					(xy 273.306032 -2.9718) (xy 273.814032 -2.9718) (xy 273.814032 -3.7338) (xy 273.306032 -3.7338)
				)
			)
		)
	)
	(footprint ""
		(layer "B.Cu")
		(at 364.381288 -48.242728 90)
		(property "Reference" "C2T33"
			(at 0 0 90)
			(layer "B.SilkS")
			(hide yes)
			(effects
				(font
					(size 1.27 1.27)
				)
				(justify mirror)
			)
		)
		(property "Value" ""
			(at 0 0 90)
			(layer "B.Fab")
			(effects
				(font
					(size 1.27 1.27)
				)
				(justify mirror)
			)
		)
		(duplicate_pad_numbers_are_jumpers no)
		(fp_poly
			(pts
				(xy -0.3048 -0.1016) (xy -0.3048 0.9906) (xy 0.3048 0.9906) (xy 0.3048 -0.1016)
			)
			(stroke
				(width 0)
				(type default)
			)
			(fill no)
			(layer "B.CrtYd")
		)
		(fp_line
			(start 0.3048 -0.1016)
			(end 0.3048 0.9906)
			(stroke
				(width 0.1)
				(type default)
			)
			(layer "B.Fab")
		)
		(fp_line
			(start -0.3048 -0.1016)
			(end 0.3048 -0.1016)
			(stroke
				(width 0.1)
				(type default)
			)
			(layer "B.Fab")
		)
		(fp_line
			(start 0.3048 0.9906)
			(end -0.3048 0.9906)
			(stroke
				(width 0.1)
				(type default)
			)
			(layer "B.Fab")
		)
		(fp_line
			(start -0.3048 0.9906)
			(end -0.3048 -0.1016)
			(stroke
				(width 0.1)
				(type default)
			)
			(layer "B.Fab")
		)
		(pad "1" smd rect
			(at 0 0 270)
			(size 0.508 0.508)
			(layers "B.Cu" "B.Mask" "B.Paste")
			(net "P3V3")
		)
		(pad "2" smd rect
			(at 0 0.889 270)
			(size 0.508 0.508)
			(layers "B.Cu" "B.Mask" "B.Paste")
			(net "GND")
		)
		(zone
			(layer "B.Cu")
			(hatch none 0.5)
			(connect_pads
				(clearance 0)
			)
			(min_thickness 0.25)
			(keepout
				(tracks allowed)
				(vias not_allowed)
				(pads allowed)
				(copperpour not_allowed)
				(footprints allowed)
			)
			(placement
				(enabled no)
				(sheetname "")
			)
			(fill
				(thermal_gap 0.5)
				(thermal_bridge_width 0.5)
				(island_removal_mode 0)
			)
			(polygon
				(pts
					(xy 364.635288 -48.496728) (xy 364.635288 -47.988728) (xy 365.016288 -47.988728) (xy 365.016288 -48.496728)
				)
			)
		)
		(zone
			(layer "B.Cu")
			(hatch none 0.5)
			(connect_pads
				(clearance 0)
			)
			(min_thickness 0.25)
			(keepout
				(tracks not_allowed)
				(vias allowed)
				(pads allowed)
				(copperpour not_allowed)
				(footprints allowed)
			)
			(placement
				(enabled no)
				(sheetname "")
			)
			(fill
				(thermal_gap 0.5)
				(thermal_bridge_width 0.5)
				(island_removal_mode 0)
			)
			(polygon
				(pts
					(xy 365.016288 -48.496728) (xy 365.016288 -47.988728) (xy 364.635288 -47.988728) (xy 364.635288 -48.496728)
				)
			)
		)
	)
	(footprint ""
		(layer "B.Cu")
		(at 471.17 -113.0554 90)
		(property "Reference" "R1M15"
			(at 0 0 90)
			(layer "B.SilkS")
			(hide yes)
			(effects
				(font
					(size 1.27 1.27)
				)
				(justify mirror)
			)
		)
		(property "Value" ""
			(at 0 0 90)
			(layer "B.Fab")
			(effects
				(font
					(size 1.27 1.27)
				)
				(justify mirror)
			)
		)
		(duplicate_pad_numbers_are_jumpers no)
		(fp_poly
			(pts
				(xy 0.2794 -0.1016) (xy -0.2794 -0.1016) (xy -0.2794 0.9906) (xy 0.2794 0.9906)
			)
			(stroke
				(width 0)
				(type default)
			)
			(fill no)
			(layer "B.CrtYd")
		)
		(fp_line
			(start 0.2794 -0.1016)
			(end 0.2794 0.9906)
			(stroke
				(width 0.1)
				(type default)
			)
			(layer "B.Fab")
		)
		(fp_line
			(start -0.2794 -0.1016)
			(end 0.2794 -0.1016)
			(stroke
				(width 0.1)
				(type default)
			)
			(layer "B.Fab")
		)
		(fp_line
			(start 0.2794 0.9906)
			(end -0.2794 0.9906)
			(stroke
				(width 0.1)
				(type default)
			)
			(layer "B.Fab")
		)
		(fp_line
			(start -0.2794 0.9906)
			(end -0.2794 -0.1016)
			(stroke
				(width 0.1)
				(type default)
			)
			(layer "B.Fab")
		)
		(pad "1" smd rect
			(at 0 0 270)
			(size 0.508 0.508)
			(layers "B.Cu" "B.Mask" "B.Paste")
			(net "RMII_BMC_OCP_CRSDV")
		)
		(pad "2" smd rect
			(at 0 0.889 270)
			(size 0.508 0.508)
			(layers "B.Cu" "B.Mask" "B.Paste")
			(net "RMII_BMC_OCP_CRSDV_R")
		)
		(zone
			(layer "B.Cu")
			(hatch none 0.5)
			(connect_pads
				(clearance 0)
			)
			(min_thickness 0.25)
			(keepout
				(tracks allowed)
				(vias not_allowed)
				(pads allowed)
				(copperpour not_allowed)
				(footprints allowed)
			)
			(placement
				(enabled no)
				(sheetname "")
			)
			(fill
				(thermal_gap 0.5)
				(thermal_bridge_width 0.5)
				(island_removal_mode 0)
			)
			(polygon
				(pts
					(xy 471.424 -113.3094) (xy 471.424 -112.8014) (xy 471.805 -112.8014) (xy 471.805 -113.3094)
				)
			)
		)
		(zone
			(layer "B.Cu")
			(hatch none 0.5)
			(connect_pads
				(clearance 0)
			)
			(min_thickness 0.25)
			(keepout
				(tracks not_allowed)
				(vias allowed)
				(pads allowed)
				(copperpour not_allowed)
				(footprints allowed)
			)
			(placement
				(enabled no)
				(sheetname "")
			)
			(fill
				(thermal_gap 0.5)
				(thermal_bridge_width 0.5)
				(island_removal_mode 0)
			)
			(polygon
				(pts
					(xy 471.805 -113.3094) (xy 471.805 -112.8014) (xy 471.424 -112.8014) (xy 471.424 -113.3094)
				)
			)
		)
	)
)
